(kicad_pcb
	(version 20260206)
	(generator "pcbnew")
	(generator_version "10.0")
	(general
		(thickness 1.6)
		(legacy_teardrops no)
	)
	(paper "A4")
	(title_block
		(title "Wiwynn_Tioga_Pass_MB.brd")
		(comment 1 "Tioga Pass / footprints 950-957 of 4770")
	)
	(layers
		(0 "F.Cu" signal "TOP")
		(4 "In1.Cu" signal "L2GND")
		(6 "In2.Cu" signal "L3")
		(8 "In3.Cu" signal "L4GND")
		(10 "In4.Cu" signal "L5")
		(12 "In5.Cu" signal "L6GND")
		(14 "In6.Cu" signal "L7VCC")
		(16 "In7.Cu" signal "L8VCC")
		(18 "In8.Cu" signal "L9GND")
		(20 "In9.Cu" signal "L10")
		(22 "In10.Cu" signal "L11GND")
		(24 "In11.Cu" signal "L12")
		(26 "In12.Cu" signal "L13GND")
		(2 "B.Cu" signal "BOTTOM")
		(9 "F.Adhes" user "F.Adhesive")
		(11 "B.Adhes" user "B.Adhesive")
		(13 "F.Paste" user "Package Geometry/Pastemask Top")
		(15 "B.Paste" user "Package Geometry/Pastemask Bottom")
		(5 "F.SilkS" user "Ref Des/Silkscreen Top")
		(7 "B.SilkS" user "Ref Des/Silkscreen Bottom")
		(1 "F.Mask" user "Board Geometry/Soldermask Top")
		(3 "B.Mask" user "Board Geometry/Soldermask Bottom")
		(17 "Dwgs.User" user "User.Drawings")
		(19 "Cmts.User" user "User.Comments")
		(21 "Eco1.User" user "User.Eco1")
		(23 "Eco2.User" user "User.Eco2")
		(25 "Edge.Cuts" user "Board Geometry/Outline")
		(27 "Margin" user)
		(31 "F.CrtYd" user "Package Geometry/Place Bound Top")
		(29 "B.CrtYd" user "Package Geometry/Place Bound Bottom")
		(35 "F.Fab" user "Ref Des/Assembly Top")
		(33 "B.Fab" user "Ref Des/Assembly Bottom")
	)
	(footprint ""
		(layer "F.Cu")
		(at 477.9264 -138.7094 90)
		(property "Reference" "R6W30"
			(at 1.01473 0.656336 0)
			(unlocked yes)
			(layer "F.SilkS")
			(effects
				(font
					(size 0.4064 0.254)
					(thickness 0.1524)
				)
			)
		)
		(property "Value" ""
			(at 0 0 90)
			(layer "F.Fab")
			(effects
				(font
					(size 1.27 1.27)
				)
			)
		)
		(duplicate_pad_numbers_are_jumpers no)
		(fp_poly
			(pts
				(xy -0.4953 -0.2032) (xy 0.4953 -0.2032) (xy 0.4953 1.6002) (xy -0.4953 1.6002)
			)
			(stroke
				(width 0)
				(type default)
			)
			(fill no)
			(layer "F.CrtYd")
		)
		(fp_line
			(start 0.4953 -0.2032)
			(end 0.4953 1.6002)
			(stroke
				(width 0.1)
				(type default)
			)
			(layer "F.Fab")
		)
		(fp_line
			(start -0.4953 -0.2032)
			(end 0.4953 -0.2032)
			(stroke
				(width 0.1)
				(type default)
			)
			(layer "F.Fab")
		)
		(fp_line
			(start 0.4953 1.6002)
			(end -0.4953 1.6002)
			(stroke
				(width 0.1)
				(type default)
			)
			(layer "F.Fab")
		)
		(fp_line
			(start -0.4953 1.6002)
			(end -0.4953 -0.2032)
			(stroke
				(width 0.1)
				(type default)
			)
			(layer "F.Fab")
		)
		(pad "1" smd rect
			(at 0 0 90)
			(size 0.762 0.889)
			(layers "F.Cu" "F.Mask" "F.Paste")
			(net "P3V3_STBY")
		)
		(pad "2" smd rect
			(at 0 1.397 90)
			(size 0.762 0.889)
			(layers "F.Cu" "F.Mask" "F.Paste")
			(net "SPA_MID_DBG2_RX_BUF")
		)
		(zone
			(layer "F.Cu")
			(hatch none 0.5)
			(connect_pads
				(clearance 0)
			)
			(min_thickness 0.25)
			(keepout
				(tracks allowed)
				(vias not_allowed)
				(pads allowed)
				(copperpour not_allowed)
				(footprints allowed)
			)
			(placement
				(enabled no)
				(sheetname "")
			)
			(fill
				(thermal_gap 0.5)
				(thermal_bridge_width 0.5)
				(island_removal_mode 0)
			)
			(polygon
				(pts
					(xy 478.8789 -139.0904) (xy 478.3709 -139.0904) (xy 478.3709 -138.3284) (xy 478.8789 -138.3284)
				)
			)
		)
		(zone
			(layer "F.Cu")
			(hatch none 0.5)
			(connect_pads
				(clearance 0)
			)
			(min_thickness 0.25)
			(keepout
				(tracks not_allowed)
				(vias allowed)
				(pads allowed)
				(copperpour not_allowed)
				(footprints allowed)
			)
			(placement
				(enabled no)
				(sheetname "")
			)
			(fill
				(thermal_gap 0.5)
				(thermal_bridge_width 0.5)
				(island_removal_mode 0)
			)
			(polygon
				(pts
					(xy 478.8789 -138.3284) (xy 478.8789 -139.0904) (xy 478.3709 -139.0904) (xy 478.3709 -138.3284)
				)
			)
		)
	)
	(footprint ""
		(layer "F.Cu")
		(at 373.2784 -131.7498 180)
		(property "Reference" "C7B24"
			(at 0 0 180)
			(layer "F.SilkS")
			(hide yes)
			(effects
				(font
					(size 1.27 1.27)
				)
			)
		)
		(property "Value" ""
			(at 0 0 180)
			(layer "F.Fab")
			(effects
				(font
					(size 1.27 1.27)
				)
			)
		)
		(duplicate_pad_numbers_are_jumpers no)
		(fp_rect
			(start -0.4953 1.6002)
			(end 0.4953 -0.2032)
			(stroke
				(width 0)
				(type default)
			)
			(fill no)
			(layer "F.CrtYd")
		)
		(fp_line
			(start 0.4953 1.6002)
			(end -0.4953 1.6002)
			(stroke
				(width 0.1)
				(type default)
			)
			(layer "F.Fab")
		)
		(fp_line
			(start 0.4953 -0.2032)
			(end 0.4953 1.6002)
			(stroke
				(width 0.1)
				(type default)
			)
			(layer "F.Fab")
		)
		(fp_line
			(start -0.4953 1.6002)
			(end -0.4953 -0.2032)
			(stroke
				(width 0.1)
				(type default)
			)
			(layer "F.Fab")
		)
		(fp_line
			(start -0.4953 -0.2032)
			(end 0.4953 -0.2032)
			(stroke
				(width 0.1)
				(type default)
			)
			(layer "F.Fab")
		)
		(pad "1" smd rect
			(at 0 0 180)
			(size 0.762 0.889)
			(layers "F.Cu" "F.Mask" "F.Paste")
			(net "P1V05_PCH_STBY")
		)
		(pad "2" smd rect
			(at 0 1.397 180)
			(size 0.762 0.889)
			(layers "F.Cu" "F.Mask" "F.Paste")
			(net "GND")
		)
		(zone
			(layer "F.Cu")
			(hatch none 0.5)
			(connect_pads
				(clearance 0)
			)
			(min_thickness 0.25)
			(keepout
				(tracks not_allowed)
				(vias allowed)
				(pads allowed)
				(copperpour not_allowed)
				(footprints allowed)
			)
			(placement
				(enabled no)
				(sheetname "")
			)
			(fill
				(thermal_gap 0.5)
				(thermal_bridge_width 0.5)
				(island_removal_mode 0)
			)
			(polygon
				(pts
					(xy 373.6594 -132.7023) (xy 372.8974 -132.7023) (xy 372.8974 -132.1943) (xy 373.6594 -132.1943)
				)
			)
		)
	)
	(footprint ""
		(layer "F.Cu")
		(at 164.973 -65.8114)
		(property "Reference" "C4D44"
			(at 0 0 0)
			(layer "F.SilkS")
			(hide yes)
			(effects
				(font
					(size 1.27 1.27)
				)
			)
		)
		(property "Value" ""
			(at 0 0 0)
			(layer "F.Fab")
			(effects
				(font
					(size 1.27 1.27)
				)
			)
		)
		(duplicate_pad_numbers_are_jumpers no)
		(fp_poly
			(pts
				(xy 0.3048 -0.1016) (xy 0.3048 0.9906) (xy -0.3048 0.9906) (xy -0.3048 -0.1016)
			)
			(stroke
				(width 0)
				(type default)
			)
			(fill no)
			(layer "F.CrtYd")
		)
		(fp_line
			(start -0.3048 -0.1016)
			(end -0.3048 0.9906)
			(stroke
				(width 0.1)
				(type default)
			)
			(layer "F.Fab")
		)
		(fp_line
			(start -0.3048 0.9906)
			(end 0.3048 0.9906)
			(stroke
				(width 0.1)
				(type default)
			)
			(layer "F.Fab")
		)
		(fp_line
			(start 0.3048 -0.1016)
			(end -0.3048 -0.1016)
			(stroke
				(width 0.1)
				(type default)
			)
			(layer "F.Fab")
		)
		(fp_line
			(start 0.3048 0.9906)
			(end 0.3048 -0.1016)
			(stroke
				(width 0.1)
				(type default)
			)
			(layer "F.Fab")
		)
		(pad "1" smd rect
			(at 0 0)
			(size 0.508 0.508)
			(layers "F.Cu" "F.Mask" "F.Paste")
			(net "VR_PVCCIO_CPU1_AVSP")
		)
		(pad "2" smd rect
			(at 0 0.889)
			(size 0.508 0.508)
			(layers "F.Cu" "F.Mask" "F.Paste")
			(net "VSENSE_PVCCIO_CPU1_AVSN")
		)
		(zone
			(layer "F.Cu")
			(hatch none 0.5)
			(connect_pads
				(clearance 0)
			)
			(min_thickness 0.25)
			(keepout
				(tracks allowed)
				(vias not_allowed)
				(pads allowed)
				(copperpour not_allowed)
				(footprints allowed)
			)
			(placement
				(enabled no)
				(sheetname "")
			)
			(fill
				(thermal_gap 0.5)
				(thermal_bridge_width 0.5)
				(island_removal_mode 0)
			)
			(polygon
				(pts
					(xy 164.719 -65.5574) (xy 165.227 -65.5574) (xy 165.227 -65.1764) (xy 164.719 -65.1764)
				)
			)
		)
		(zone
			(layer "F.Cu")
			(hatch none 0.5)
			(connect_pads
				(clearance 0)
			)
			(min_thickness 0.25)
			(keepout
				(tracks not_allowed)
				(vias allowed)
				(pads allowed)
				(copperpour not_allowed)
				(footprints allowed)
			)
			(placement
				(enabled no)
				(sheetname "")
			)
			(fill
				(thermal_gap 0.5)
				(thermal_bridge_width 0.5)
				(island_removal_mode 0)
			)
			(polygon
				(pts
					(xy 164.719 -65.1764) (xy 165.227 -65.1764) (xy 165.227 -65.5574) (xy 164.719 -65.5574)
				)
			)
		)
	)
	(footprint ""
		(layer "F.Cu")
		(at 198.042276 -92.967048 90)
		(property "Reference" "C4C19"
			(at 0 0 90)
			(layer "F.SilkS")
			(hide yes)
			(effects
				(font
					(size 1.27 1.27)
				)
			)
		)
		(property "Value" ""
			(at 0 0 90)
			(layer "F.Fab")
			(effects
				(font
					(size 1.27 1.27)
				)
			)
		)
		(duplicate_pad_numbers_are_jumpers no)
		(fp_rect
			(start 0.3048 0.9906)
			(end -0.3048 -0.1016)
			(stroke
				(width 0)
				(type default)
			)
			(fill no)
			(layer "F.CrtYd")
		)
		(fp_line
			(start 0.3048 -0.1016)
			(end -0.3048 -0.1016)
			(stroke
				(width 0.1)
				(type default)
			)
			(layer "F.Fab")
		)
		(fp_line
			(start -0.3048 -0.1016)
			(end -0.3048 0.9906)
			(stroke
				(width 0.1)
				(type default)
			)
			(layer "F.Fab")
		)
		(fp_line
			(start 0.3048 0.9906)
			(end 0.3048 -0.1016)
			(stroke
				(width 0.1)
				(type default)
			)
			(layer "F.Fab")
		)
		(fp_line
			(start -0.3048 0.9906)
			(end 0.3048 0.9906)
			(stroke
				(width 0.1)
				(type default)
			)
			(layer "F.Fab")
		)
		(pad "1" smd rect
			(at 0 0 90)
			(size 0.508 0.508)
			(layers "F.Cu" "F.Mask" "F.Paste")
			(net "VR_FET_SW_P12V_STBY_PVCCIN_CPU0")
		)
		(pad "2" smd rect
			(at 0 0.889 90)
			(size 0.508 0.508)
			(layers "F.Cu" "F.Mask" "F.Paste")
			(net "GND")
		)
		(zone
			(layer "F.Cu")
			(hatch none 0.5)
			(connect_pads
				(clearance 0)
			)
			(min_thickness 0.25)
			(keepout
				(tracks allowed)
				(vias not_allowed)
				(pads allowed)
				(copperpour not_allowed)
				(footprints allowed)
			)
			(placement
				(enabled no)
				(sheetname "")
			)
			(fill
				(thermal_gap 0.5)
				(thermal_bridge_width 0.5)
				(island_removal_mode 0)
			)
			(polygon
				(pts
					(xy 198.677276 -93.221048) (xy 198.296276 -93.221048) (xy 198.296276 -92.713048) (xy 198.677276 -92.713048)
				)
			)
		)
		(zone
			(layer "F.Cu")
			(hatch none 0.5)
			(connect_pads
				(clearance 0)
			)
			(min_thickness 0.25)
			(keepout
				(tracks not_allowed)
				(vias allowed)
				(pads allowed)
				(copperpour not_allowed)
				(footprints allowed)
			)
			(placement
				(enabled no)
				(sheetname "")
			)
			(fill
				(thermal_gap 0.5)
				(thermal_bridge_width 0.5)
				(island_removal_mode 0)
			)
			(polygon
				(pts
					(xy 198.677276 -93.221048) (xy 198.296276 -93.221048) (xy 198.296276 -92.713048) (xy 198.677276 -92.713048)
				)
			)
		)
	)
	(footprint ""
		(layer "F.Cu")
		(at 94.45244 -73.318116)
		(property "Reference" "C2D31"
			(at 0 0 0)
			(layer "F.SilkS")
			(hide yes)
			(effects
				(font
					(size 1.27 1.27)
				)
			)
		)
		(property "Value" ""
			(at 0 0 0)
			(layer "F.Fab")
			(effects
				(font
					(size 1.27 1.27)
				)
			)
		)
		(duplicate_pad_numbers_are_jumpers no)
		(fp_poly
			(pts
				(xy -0.4953 -0.2032) (xy 0.4953 -0.2032) (xy 0.4953 1.6002) (xy -0.4953 1.6002)
			)
			(stroke
				(width 0)
				(type default)
			)
			(fill no)
			(layer "F.CrtYd")
		)
		(fp_line
			(start -0.4953 -0.2032)
			(end 0.4953 -0.2032)
			(stroke
				(width 0.1)
				(type default)
			)
			(layer "F.Fab")
		)
		(fp_line
			(start -0.4953 1.6002)
			(end -0.4953 -0.2032)
			(stroke
				(width 0.1)
				(type default)
			)
			(layer "F.Fab")
		)
		(fp_line
			(start 0.4953 -0.2032)
			(end 0.4953 1.6002)
			(stroke
				(width 0.1)
				(type default)
			)
			(layer "F.Fab")
		)
		(fp_line
			(start 0.4953 1.6002)
			(end -0.4953 1.6002)
			(stroke
				(width 0.1)
				(type default)
			)
			(layer "F.Fab")
		)
		(pad "1" smd rect
			(at 0 0)
			(size 0.762 0.889)
			(layers "F.Cu" "F.Mask" "F.Paste")
			(net "PVCCIN_CPU1")
		)
		(pad "2" smd rect
			(at 0 1.397)
			(size 0.762 0.889)
			(layers "F.Cu" "F.Mask" "F.Paste")
			(net "GND")
		)
		(zone
			(layer "F.Cu")
			(hatch none 0.5)
			(connect_pads
				(clearance 0)
			)
			(min_thickness 0.25)
			(keepout
				(tracks not_allowed)
				(vias allowed)
				(pads allowed)
				(copperpour not_allowed)
				(footprints allowed)
			)
			(placement
				(enabled no)
				(sheetname "")
			)
			(fill
				(thermal_gap 0.5)
				(thermal_bridge_width 0.5)
				(island_removal_mode 0)
			)
			(polygon
				(pts
					(xy 94.07144 -72.873616) (xy 94.83344 -72.873616) (xy 94.83344 -72.365616) (xy 94.07144 -72.365616)
				)
			)
		)
	)
	(footprint ""
		(layer "F.Cu")
		(at 437.690006 -41.663874 180)
		(property "Reference" "R25W25"
			(at 0 0 180)
			(layer "F.SilkS")
			(hide yes)
			(effects
				(font
					(size 1.27 1.27)
				)
			)
		)
		(property "Value" "*"
			(at 0.064008 -4.108196 180)
			(unlocked yes)
			(layer "F.Fab")
			(hide yes)
			(effects
				(font
					(size 1.27 1.016)
					(thickness 0.1524)
				)
			)
		)
		(property "Device Type" "120R2F-GP_RCL_GP-120R2F-GP,64.A"
			(at 0.064008 -5.632196 180)
			(unlocked yes)
			(layer "F.Fab")
			(hide yes)
			(effects
				(font
					(size 1.27 1.016)
					(thickness 0.1524)
				)
			)
		)
		(duplicate_pad_numbers_are_jumpers no)
		(fp_line
			(start 0.508 -0.9398)
			(end -0.508 -0.9398)
			(stroke
				(width 0.1524)
				(type default)
			)
			(layer "F.SilkS")
		)
		(fp_line
			(start -0.508 -0.9398)
			(end -0.508 0.9398)
			(stroke
				(width 0.1524)
				(type default)
			)
			(layer "F.SilkS")
		)
		(fp_rect
			(start -0.508 0.9398)
			(end 0.508 -0.9398)
			(stroke
				(width 0)
				(type default)
			)
			(fill no)
			(layer "F.CrtYd")
		)
		(fp_rect
			(start -0.508 0.9398)
			(end 0.508 -0.9398)
			(stroke
				(width 0)
				(type default)
			)
			(fill no)
			(layer "F.Fab")
		)
		(pad "1" smd custom
			(at 0 -0.4445 180)
			(size 0.1397 0.1397)
			(layers "F.Cu" "F.Mask" "F.Paste")
			(net "GND")
			(options
				(clearance outline)
				(anchor circle)
			)
			(primitives
				(gr_poly
					(pts
						(arc
							(start -0.1778 -0.2794)
							(mid -0.249642 -0.249642)
							(end -0.2794 -0.1778)
						)
						(arc
							(start -0.2794 0.1778)
							(mid -0.249642 0.249642)
							(end -0.1778 0.2794)
						)
						(arc
							(start 0.1778 0.2794)
							(mid 0.249642 0.249642)
							(end 0.2794 0.1778)
						)
						(arc
							(start 0.2794 -0.1778)
							(mid 0.249642 -0.249642)
							(end 0.1778 -0.2794)
						)
					)
					(width 0)
					(fill yes)
				)
			)
		)
		(pad "2" smd custom
			(at 0 0.4445 180)
			(size 0.1397 0.1397)
			(layers "F.Cu" "F.Mask" "F.Paste")
			(net "BMC_M_A13")
			(options
				(clearance outline)
				(anchor circle)
			)
			(primitives
				(gr_poly
					(pts
						(arc
							(start -0.1778 -0.2794)
							(mid -0.249642 -0.249642)
							(end -0.2794 -0.1778)
						)
						(arc
							(start -0.2794 0.1778)
							(mid -0.249642 0.249642)
							(end -0.1778 0.2794)
						)
						(arc
							(start 0.1778 0.2794)
							(mid 0.249642 0.249642)
							(end 0.2794 0.1778)
						)
						(arc
							(start 0.2794 -0.1778)
							(mid 0.249642 -0.249642)
							(end 0.1778 -0.2794)
						)
					)
					(width 0)
					(fill yes)
				)
			)
		)
	)
	(footprint ""
		(layer "F.Cu")
		(at 353.2505 -152.273 -90)
		(property "Reference" "RT30"
			(at 1.01473 0.656336 180)
			(unlocked yes)
			(layer "F.SilkS")
			(effects
				(font
					(size 0.4064 0.254)
					(thickness 0.1524)
				)
			)
		)
		(property "Value" ""
			(at 0 0 270)
			(layer "F.Fab")
			(effects
				(font
					(size 1.27 1.27)
				)
			)
		)
		(duplicate_pad_numbers_are_jumpers no)
		(fp_poly
			(pts
				(xy -0.4953 -0.2032) (xy 0.4953 -0.2032) (xy 0.4953 1.6002) (xy -0.4953 1.6002)
			)
			(stroke
				(width 0)
				(type default)
			)
			(fill no)
			(layer "F.CrtYd")
		)
		(fp_line
			(start -0.4953 1.6002)
			(end -0.4953 -0.2032)
			(stroke
				(width 0.1)
				(type default)
			)
			(layer "F.Fab")
		)
		(fp_line
			(start 0.4953 1.6002)
			(end -0.4953 1.6002)
			(stroke
				(width 0.1)
				(type default)
			)
			(layer "F.Fab")
		)
		(fp_line
			(start -0.4953 -0.2032)
			(end 0.4953 -0.2032)
			(stroke
				(width 0.1)
				(type default)
			)
			(layer "F.Fab")
		)
		(fp_line
			(start 0.4953 -0.2032)
			(end 0.4953 1.6002)
			(stroke
				(width 0.1)
				(type default)
			)
			(layer "F.Fab")
		)
		(pad "1" smd rect
			(at 0 0 270)
			(size 0.762 0.889)
			(layers "F.Cu" "F.Mask" "F.Paste")
			(net "VR_PVDDQ_DEF_PH1_BOOT")
		)
		(pad "2" smd rect
			(at 0 1.397 270)
			(size 0.762 0.889)
			(layers "F.Cu" "F.Mask" "F.Paste")
			(net "VR_PVDDQ_DEF_PH1_BOOT_R")
		)
		(zone
			(layer "F.Cu")
			(hatch none 0.5)
			(connect_pads
				(clearance 0)
			)
			(min_thickness 0.25)
			(keepout
				(tracks not_allowed)
				(vias allowed)
				(pads allowed)
				(copperpour not_allowed)
				(footprints allowed)
			)
			(placement
				(enabled no)
				(sheetname "")
			)
			(fill
				(thermal_gap 0.5)
				(thermal_bridge_width 0.5)
				(island_removal_mode 0)
			)
			(polygon
				(pts
					(xy 352.298 -152.654) (xy 352.298 -151.892) (xy 352.806 -151.892) (xy 352.806 -152.654)
				)
			)
		)
		(zone
			(layer "F.Cu")
			(hatch none 0.5)
			(connect_pads
				(clearance 0)
			)
			(min_thickness 0.25)
			(keepout
				(tracks allowed)
				(vias not_allowed)
				(pads allowed)
				(copperpour not_allowed)
				(footprints allowed)
			)
			(placement
				(enabled no)
				(sheetname "")
			)
			(fill
				(thermal_gap 0.5)
				(thermal_bridge_width 0.5)
				(island_removal_mode 0)
			)
			(polygon
				(pts
					(xy 352.298 -151.892) (xy 352.806 -151.892) (xy 352.806 -152.654) (xy 352.298 -152.654)
				)
			)
		)
	)
	(footprint ""
		(layer "F.Cu")
		(at 40.036496 -81.415382)
		(property "Reference" "L1D1"
			(at 3.378708 -4.251706 0)
			(unlocked yes)
			(layer "F.SilkS")
			(effects
				(font
					(size 0.4064 0.254)
					(thickness 0.1524)
				)
			)
		)
		(property "Value" ""
			(at 0 0 0)
			(layer "F.Fab")
			(effects
				(font
					(size 1.27 1.27)
				)
			)
		)
		(duplicate_pad_numbers_are_jumpers no)
		(fp_line
			(start -1.1303 -3.199892)
			(end 8.3693 -3.199892)
			(stroke
				(width 0.1524)
				(type default)
			)
			(layer "F.SilkS")
		)
		(fp_line
			(start -1.1303 -1.6637)
			(end -1.1303 -3.199892)
			(stroke
				(width 0.1524)
				(type default)
			)
			(layer "F.SilkS")
		)
		(fp_line
			(start -1.1303 3.199892)
			(end -1.1303 1.6637)
			(stroke
				(width 0.1524)
				(type default)
			)
			(layer "F.SilkS")
		)
		(fp_line
			(start 8.3693 -3.199892)
			(end 8.3693 -1.6637)
			(stroke
				(width 0.1524)
				(type default)
			)
			(layer "F.SilkS")
		)
		(fp_line
			(start 8.3693 1.6637)
			(end 8.3693 3.199892)
			(stroke
				(width 0.1524)
				(type default)
			)
			(layer "F.SilkS")
		)
		(fp_line
			(start 8.3693 3.199892)
			(end -1.1303 3.199892)
			(stroke
				(width 0.1524)
				(type default)
			)
			(layer "F.SilkS")
		)
		(fp_rect
			(start -1.1303 3.199892)
			(end 8.3693 -3.199892)
			(stroke
				(width 0)
				(type default)
			)
			(fill no)
			(layer "F.CrtYd")
		)
		(fp_line
			(start -1.1303 -3.199892)
			(end 8.3693 -3.199892)
			(stroke
				(width 0.1)
				(type default)
			)
			(layer "F.Fab")
		)
		(fp_line
			(start -1.1303 3.199892)
			(end -1.1303 -3.199892)
			(stroke
				(width 0.1)
				(type default)
			)
			(layer "F.Fab")
		)
		(fp_line
			(start 8.3693 -3.199892)
			(end 8.3693 3.199892)
			(stroke
				(width 0.1)
				(type default)
			)
			(layer "F.Fab")
		)
		(fp_line
			(start 8.3693 3.199892)
			(end -1.1303 3.199892)
			(stroke
				(width 0.1)
				(type default)
			)
			(layer "F.Fab")
		)
		(pad "1" smd rect
			(at 0 0)
			(size 3.683 2.667)
			(layers "F.Cu" "F.Mask" "F.Paste")
			(net "VR_PVCCIN_CPU1_PHASE4")
		)
		(pad "2" smd rect
			(at 7.239 0)
			(size 3.683 2.667)
			(layers "F.Cu" "F.Mask" "F.Paste")
			(net "PVCCIN_CPU1")
		)
	)
)
